FILE_TYPE = CONNECTIVITY;
{Allegro Design Entry HDL 17.2-2016 S081 (4005846) 1/11/2022}
"PAGE_NUMBER" = 192;
0"NC";
1"P3V3_AUX\g";
2"P3V3_AUX\g";
3"P3V3_AUX\g";
4"P3V3_AUX\g";
5"P3V3_AUX\g";
6"PGPPA_AUX\g";
7"P3V3_AUX\g";
8"P1V05_PCH_AUX\g";
9"ESPI_ALERT1_N_LPC_RCIN_N";
10"IRQ_LPC_PIRQA_N_ESPI_ALERT0_N";
11"IRQ_PCH_SCI_WHEA_N";
12"IRQ_LPC_SERIRQ_ESPI_CS1_N";
13"H_CPU_ERR1_PCH_R_N";
14"H_CPU_ERR0_PCH_R_N";
15"H_CPU_ERR2_PCH_R_N"CDS_PHYS_NET_NAME"H_CPU_ERR0_PCH_N";
16"FM_DEBUG_PORT_PRSNT_R_N";
17"FM_PCHHOT_N";
18"IRQ_TPM_SPI_N";
19"PU_PCH_PMCALERT_N";
20"FM_ME_AUTHN_FAIL";
21"FM_ME_BT_DONE";
22"FM_PS_PWROK_DLY_R_SEL";
23"IRQ_PCH_CPU_NMI_EVENT_R_N";
24"IRQ_SMI_ACTIVE_N";
25"FM_THROTTLE_N";
26"FM_BIOS_POST_CMPLT_N";
27"PU_LPC_PME_N";
28"FM_PCH_GLB_RST_WARN_N";
29"PU_PCH_VRALERT_N";
%"Q_RES"
"1","(1150,3150)","0","pure_quanta","I1";
;
PART_NUMBER"CS21002FB06"
VALUE"1K"
WATTAGE"1/16W"
MATERIAL"CHIP"
TOLERANCE"1%"
PACK_TYPE"0402LF"
$LOCATION"R3040"
CDS_LIB"pure_quanta"
CDS_LOCATION"R3040"
$SEC"1"
CDS_SEC"1";
"B"
$PN"2"11;
"A"
$PN"1"7;
%"Q_RES"
"1","(1200,1050)","0","pure_quanta","I11";
;
PART_NUMBER"CS31002FB08"
MATERIAL"EMPTY"
VALUE"10K"
TOLERANCE"1%"
$LOCATION"R1262"
CDS_LIB"pure_quanta"
PACK_TYPE"0402LF"
WATTAGE"1/16W"
CDS_LOCATION"R1262"
$SEC"1"
CDS_SEC"1";
"B"
$PN"2"15;
"A"
$PN"1"8;
%"UNIVERSAL_POWER"
"1","(825,1600)","0","logical_power","I12";
;
HDL_POWER"P1V05_PCH_AUX"
CDS_LIB"logical_power";
"A"8;
%"Q_RES"
"1","(1200,1300)","0","pure_quanta","I17";
;
PART_NUMBER"CS31002FB08"
TOLERANCE"1%"
MATERIAL"EMPTY"
VALUE"10K"
WATTAGE"1/16W"
PACK_TYPE"0402LF"
$LOCATION"R1260"
CDS_LIB"pure_quanta"
CDS_LOCATION"R1260"
$SEC"1"
CDS_SEC"1";
"B"
$PN"2"14;
"A"
$PN"1"8;
%"Q_RES"
"1","(1200,1175)","0","pure_quanta","I18";
;
PART_NUMBER"CS31002FB08"
TOLERANCE"1%"
MATERIAL"EMPTY"
VALUE"10K"
$LOCATION"R3042"
WATTAGE"1/16W"
PACK_TYPE"0402LF"
CDS_LIB"pure_quanta"
CDS_LOCATION"R3042"
$SEC"1"
CDS_SEC"1";
"B"
$PN"2"13;
"A"
$PN"1"8;
%"UNIVERSAL_POWER"
"1","(800,3375)","0","logical_power","I2";
;
HDL_POWER"P3V3_AUX"
CDS_LIB"logical_power";
"A"7;
%"Q_RES"
"1","(-4950,3125)","0","pure_quanta","I23";
;
PART_NUMBER"CS21002FB06"
VALUE"1K"
TOLERANCE"1%"
MATERIAL"CHIP"
PACK_TYPE"0402LF"
WATTAGE"1/16W"
$LOCATION"R1253"
CDS_LIB"pure_quanta"
CDS_LOCATION"R1253"
$SEC"1"
CDS_SEC"1";
"B"
$PN"2"10;
"A"
$PN"1"6;
%"Q_RES"
"1","(-4950,3000)","0","pure_quanta","I24";
;
PART_NUMBER"CS31002FB08"
VALUE"10K"
MATERIAL"CHIP"
TOLERANCE"1%"
$LOCATION"R1254"
CDS_LIB"pure_quanta"
PACK_TYPE"0402LF"
WATTAGE"1/16W"
CDS_LOCATION"R1254"
$SEC"1"
CDS_SEC"1";
"B"
$PN"2"12;
"A"
$PN"1"6;
%"UNIVERSAL_POWER"
"1","(-5300,3425)","0","logical_power","I25";
;
HDL_POWER"PGPPA_AUX"
CDS_LIB"logical_power";
"A"6;
%"Q_RES"
"1","(-4950,2875)","0","pure_quanta","I26";
;
PART_NUMBER"CS21002FB06"
VALUE"1K"
TOLERANCE"1%"
MATERIAL"CHIP"
WATTAGE"1/16W"
PACK_TYPE"0402LF"
$LOCATION"R1255"
CDS_LIB"pure_quanta"
CDS_LOCATION"R1255"
$SEC"1"
CDS_SEC"1";
"B"
$PN"2"9;
"A"
$PN"1"6;
%"UNIVERSAL_POWER"
"1","(-2200,3450)","0","logical_power","I39";
;
HDL_POWER"P3V3_AUX"
CDS_LIB"logical_power";
"A"5;
%"Q_RES"
"1","(1150,3025)","0","pure_quanta","I4";
;
PART_NUMBER"CS31002FB08"
MATERIAL"CHIP"
VALUE"10K"
TOLERANCE"1%"
$LOCATION"R1257"
CDS_LIB"pure_quanta"
PACK_TYPE"0402LF"
WATTAGE"1/16W"
CDS_LOCATION"R1257"
$SEC"1"
CDS_SEC"1";
"B"
$PN"2"29;
"A"
$PN"1"7;
%"Q_RES"
"1","(-1850,3025)","0","pure_quanta","I41";
;
PART_NUMBER"CS31002FB08"
MATERIAL"CHIP"
TOLERANCE"1%"
VALUE"10K"
$LOCATION"R1449"
CDS_LIB"pure_quanta"
WATTAGE"1/16W"
PACK_TYPE"0402LF"
CDS_LOCATION"R1449"
$SEC"1"
CDS_SEC"1";
"B"
$PN"2"26;
"A"
$PN"1"5;
%"Q_RES"
"1","(-1850,2900)","0","pure_quanta","I42";
;
PART_NUMBER"CS31002FB08"
VALUE"10K"
MATERIAL"CHIP"
TOLERANCE"1%"
$LOCATION"R1450"
PACK_TYPE"0402LF"
WATTAGE"1/16W"
CDS_LIB"pure_quanta"
CDS_LOCATION"R1450"
$SEC"1"
CDS_SEC"1";
"B"
$PN"2"25;
"A"
$PN"1"5;
%"UNIVERSAL_POWER"
"1","(825,-575)","0","logical_power","I49";
;
HDL_POWER"P3V3_AUX"
CDS_LIB"logical_power";
"A"4;
%"Q_RES"
"1","(1200,-850)","0","pure_quanta","I50";
;
PART_NUMBER"CS31002FB08"
VALUE"10K"
TOLERANCE"1%"
MATERIAL"CHIP"
WATTAGE"1/16W"
PACK_TYPE"0402LF"
$LOCATION"R1458"
CDS_LIB"pure_quanta"
CDS_LOCATION"R1458"
$SEC"1"
CDS_SEC"1";
"B"
$PN"2"24;
"A"
$PN"1"4;
%"Q_RES"
"1","(1200,-975)","0","pure_quanta","I51";
;
PART_NUMBER"CS31002FB08"
VALUE"10K"
TOLERANCE"1%"
MATERIAL"CHIP"
$LOCATION"R1459"
WATTAGE"1/16W"
PACK_TYPE"0402LF"
CDS_LIB"pure_quanta"
CDS_LOCATION"R1459"
$SEC"1"
CDS_SEC"1";
"B"
$PN"2"23;
"A"
$PN"1"4;
%"UNIVERSAL_POWER"
"1","(-5300,1600)","0","logical_power","I58";
;
HDL_POWER"P3V3_AUX"
CDS_LIB"logical_power";
"A"3;
%"Q_RES"
"1","(-4950,1300)","0","pure_quanta","I59";
;
PART_NUMBER"CS31002FB08"
MATERIAL"CHIP"
WATTAGE"1/16W"
PACK_TYPE"0402LF"
TOLERANCE"1%"
VALUE"10K"
$LOCATION"R8"
CDS_LIB"pure_quanta"
CDS_LOCATION"R8"
$SEC"1"
CDS_SEC"1";
"B"
$PN"2"22;
"A"
$PN"1"3;
%"Q_RES"
"1","(1150,2875)","0","pure_quanta","I6";
;
PART_NUMBER"CS31002FB08"
VALUE"10K"
TOLERANCE"1%"
MATERIAL"CHIP"
$LOCATION"R3041"
WATTAGE"1/16W"
PACK_TYPE"0402LF"
CDS_LIB"pure_quanta"
CDS_LOCATION"R3041"
$SEC"1"
CDS_SEC"1";
"B"
$PN"2"28;
"A"
$PN"1"7;
%"Q_RES"
"1","(-4950,1175)","0","pure_quanta","I60";
;
PART_NUMBER"CS31002FB08"
TOLERANCE"1%"
VALUE"10K"
MATERIAL"CHIP"
$LOCATION"R71"
CDS_LIB"pure_quanta"
PACK_TYPE"0402LF"
WATTAGE"1/16W"
CDS_LOCATION"R71"
$SEC"1"
CDS_SEC"1";
"B"
$PN"2"21;
"A"
$PN"1"3;
%"Q_RES"
"1","(-4950,1050)","0","pure_quanta","I62";
;
PART_NUMBER"CS31002FB08"
MATERIAL"CHIP"
TOLERANCE"1%"
VALUE"10K"
$LOCATION"R1554"
CDS_LIB"pure_quanta"
PACK_TYPE"0402LF"
WATTAGE"1/16W"
CDS_LOCATION"R1554"
$SEC"1"
CDS_SEC"1";
"B"
$PN"2"20;
"A"
$PN"1"3;
%"UNIVERSAL_POWER"
"1","(-2200,1600)","0","logical_power","I65";
;
HDL_POWER"P3V3_AUX"
CDS_LIB"logical_power";
"A"2;
%"Q_RES"
"1","(-1850,1300)","0","pure_quanta","I66";
;
PART_NUMBER"CS31002FB08"
PACK_TYPE"0402LF"
WATTAGE"1/16W"
MATERIAL"CHIP"
VALUE"10K"
TOLERANCE"1%"
$LOCATION"R456"
CDS_LIB"pure_quanta"
CDS_LOCATION"R456"
$SEC"1"
CDS_SEC"1";
"B"
$PN"2"19;
"A"
$PN"1"2;
%"UNIVERSAL_POWER"
"1","(-5300,-550)","0","logical_power","I67";
;
HDL_POWER"P3V3_AUX"
CDS_LIB"logical_power";
"A"1;
%"Q_RES"
"1","(-4925,-850)","0","pure_quanta","I69";
;
PART_NUMBER"CS31002FB08"
WATTAGE"1/16W"
VALUE"10K"
TOLERANCE"1%"
PACK_TYPE"0402LF"
MATERIAL"EMPTY"
$LOCATION"R401"
CDS_LIB"pure_quanta"
CDS_LOCATION"R401"
$SEC"1"
CDS_SEC"1";
"B"
$PN"2"18;
"A"
$PN"1"1;
%"Q_RES"
"1","(1150,2625)","0","pure_quanta","I72";
;
PART_NUMBER"CS31002FB08"
MATERIAL"CHIP"
TOLERANCE"1%"
VALUE"10K"
$LOCATION"R1955"
CDS_LIB"pure_quanta"
WATTAGE"1/16W"
PACK_TYPE"0402LF"
CDS_LOCATION"R1955"
$SEC"1"
CDS_SEC"1";
"B"
$PN"2"17;
"A"
$PN"1"7;
%"Q_RES"
"1","(-4950,925)","0","pure_quanta","I75";
;
PART_NUMBER"CS31002FB08"
MATERIAL"CHIP"
TOLERANCE"1%"
VALUE"10K"
$LOCATION"R2342"
CDS_LIB"pure_quanta"
PACK_TYPE"0402LF"
WATTAGE"1/16W"
CDS_LOCATION"R2342"
$SEC"1"
CDS_SEC"1";
"B"
$PN"2"16;
"A"
$PN"1"3;
%"Q_RES"
"1","(1150,2750)","0","pure_quanta","I8";
;
PART_NUMBER"CS31002FB08"
MATERIAL"CHIP"
VALUE"10K"
TOLERANCE"1%"
$LOCATION"R1259"
WATTAGE"1/16W"
PACK_TYPE"0402LF"
CDS_LIB"pure_quanta"
CDS_LOCATION"R1259"
$SEC"1"
CDS_SEC"1";
"B"
$PN"2"27;
"A"
$PN"1"7;
END.
